FILE_TYPE = CONNECTIVITY;
{Allegro Design Entry HDL 16.6-p007 (v16-6-112F) 10/10/2012}
"PAGE_NUMBER" = 141;
0"NC";
1"GND\g";
2"GND\g";
3"GND\g";
4"P3V3_STBY\g";
5"GND\g";
6"GND\g";
7"GND\g";
8"GND\g";
9"GND\g";
10"NIC_LED_ACT_ANODE_R";
11"LED_LAN_1_R_N";
12"GND_LAN_TRCT1234_C";
13"NIC_MDI_SPRV_RJ45_3_R_DN";
14"NIC_MDI_SPRV_RJ45_3_R_DP";
15"NIC_MDI_SPRV_RJ45_2_R_DN";
16"NIC_MDI_SPRV_RJ45_2_R_DP";
17"NIC_MDI_MNG_TX_DP";
18"NIC_MDI_MNG_TX_DN";
19"LED_LAN_1_N";
20"NIC_SET_P_MDI_2_DP";
21"NIC_MDI_SPRV_RJ45_1_DN";
22"NIC_MDI_SPRV_RJ45_1_DP";
23"NIC_MDI_SPRV_RJ45_0_DN";
24"NIC_MDI_SPRV_RJ45_0_DP";
25"LED_LAN_2_N";
26"NIC_SER_P_MDI_3_DP";
27"LED_LAN_0_N";
28"NIC_SER_N_MDI_3_DN";
29"NIC_SET_N_MDI_2_DN";
30"NIC_MDI_MNG_RX_DN";
31"NIC_MDI_SPRV_RJ45_0_R_DP";
32"NIC_MDI_SPRV_RJ45_0_R_DN";
33"NIC_MDI_SPRV_RJ45_3_R_DP";
34"GND_LAN_TRCT1234_C"VOLTAGE"0";
35"NIC_MDI_SPRV_RJ45_0_R_DN";
36"GND_LAN_TRCT1234_C";
37"NIC_MDI_SPRV_RJ45_1_R_DP";
38"NIC_MDI_SPRV_RJ45_0_R_DP";
39"LED_LAN_0_R_N";
40"LED_LAN_2_R_N";
41"NIC_MDI_SPRV_RJ45_1_R_DN";
42"NIC_MDI_SPRV_RJ45_1_R_DP";
43"NIC_MDI_SPRV_RJ45_2_R_DP";
44"NIC_MDI_SPRV_RJ45_3_R_DN";
45"NIC_MDI_SPRV_RJ45_2_R_DN";
46"NIC_MDI_MNG_RX_DP";
47"NIC_MDI_SPRV_RJ45_1_R_DN";
%"CAP"
"2","(-3150,4375)","0","mstr_discrete","I100";
;
PACK_TYPE"0402LF"
MATERIAL"EMPTY"
VOLTAGE"50V"
LOCATION"C9G12"
VALUE"4700PF"
PART_NUMBER"A36096-066"
TOLERANCE"10%"
GROUP"NI_I210&RJ45"
BOM_COST"NT_GBE_BASE"
ROOM"NIC_SPRV"
NO_XNET_CONNECTION"1"
$SEC"1"
CDS_SEC"1"
CDS_LIB"mstr_discrete"
CDS_LOCATION"C9G12";
"A"
$PN"1"28;
"B"
$PN"2"30;
%"CAP"
"2","(-2825,4075)","0","mstr_discrete","I101";
;
CDS_SEC"1"
GROUP"NI_I210&RJ45"
PACK_TYPE"0402LF"
VALUE"4700PF"
PART_NUMBER"A36096-066"
VOLTAGE"50V"
LOCATION"C9G16"
TOLERANCE"10%"
MATERIAL"EMPTY"
ROOM"NIC_SPRV"
BOM_COST"NT_GBE_BASE"
NO_XNET_CONNECTION"1"
CDS_LOCATION"C9G16"
CDS_LIB"mstr_discrete"
SEC"1"
SEC_TYPE"0402LF";
"A"
$PN"1"20;
"B"
$PN"2"17;
%"CAP"
"2","(-3100,4025)","0","mstr_discrete","I102";
;
CDS_SEC"1"
VALUE"4700PF"
GROUP"NI_I210&RJ45"
PACK_TYPE"0402LF"
MATERIAL"EMPTY"
VOLTAGE"50V"
PART_NUMBER"A36096-066"
TOLERANCE"10%"
LOCATION"C9G13"
BOM_COST"NT_GBE_BASE"
NO_XNET_CONNECTION"1"
ROOM"NIC_SPRV"
CDS_LIB"mstr_discrete"
CDS_LOCATION"C9G13"
SEC"1"
SEC_TYPE"0402LF";
"A"
$PN"1"29;
"B"
$PN"2"18;
%"SKT-RJ45-LED-XFOR-1-GP"
"1","(-1650,1825)","0","w_hdl","I129";
;
CDS_SEC"1"
CDS_LOCATION"JA9G1"
LOCATION"JA9G1"
VALUE"SKT-RJ45-LED-XFOR-1-GP"
GROUP"NI_I210&RJ45"
CDS_LMAN_SYM_OUTLINE"-250,625,250,-625"
CDS_LIB"w_hdl"
PART_NUMBER"022.10001.0S51"
SEC_TYPE"SOCKET-G2"
SEC"1"
PACK_TYPE"SOCKET-G2";
"2"
$PN"2"8;
"1"
$PN"1"7;
"R11"
$PN"R11"12;
"R10"
$PN"R10"13;
"R9"
$PN"R9"14;
"R8"
$PN"R8"15;
"R7"
$PN"R7"16;
"R6"
$PN"R6"3;
"R5"
$PN"R5"47;
"R4"
$PN"R4"37;
"R3"
$PN"R3"35;
"R2"
$PN"R2"38;
"R1"
$PN"R1"36;
"L4"
$PN"L4"10;
"L3"
$PN"L3"11;
"L2"
$PN"L2"39;
"L1"
$PN"L1"40;
%"RES"
"1","(-2800,2725)","4","mstr_discrete","I134";
;
MATERIAL"CHIP"
PACK_TYPE"0402"
WATTAGE"1/16W"
LOCATION"R9G2"
VALUE"75"
GROUP"NI_I210&RJ45"
TOLERANCE"1.0%"
PART_NUMBER"G21796-267"
BOM_COST"PROC"
CDS_LIB"mstr_discrete"
CDS_SEC"1"
$SEC"1"
ROOM"PROC_SIDEBAND"
CDS_LOCATION"R9G2";
"B"
$PN"2"25;
"A"
$PN"1"40;
%"RES"
"1","(-2800,2525)","4","mstr_discrete","I135";
;
PART_NUMBER"G21796-267"
MATERIAL"CHIP"
WATTAGE"1/16W"
TOLERANCE"1.0%"
LOCATION"R9G3"
VALUE"75"
GROUP"NI_I210&RJ45"
PACK_TYPE"0402"
ROOM"PROC_SIDEBAND"
$SEC"1"
CDS_SEC"1"
CDS_LIB"mstr_discrete"
BOM_COST"PROC"
CDS_LOCATION"R9G3";
"B"
$PN"2"27;
"A"
$PN"1"39;
%"CAP"
"1","(-3350,2375)","0","mstr_discrete","I138";
;
TOLERANCE"10%"
PACK_TYPE"0402LF"
MATERIAL"X7R"
PART_NUMBER"A36096-049"
VOLTAGE"50V"
VALUE"470PF"
LOCATION"C9G3"
GROUP"NI_I210&RJ45"
CDS_SEC"1"
SEC_TYPE"0402LF"
CDS_LOCATION"C9G3"
SEC"1"
BOM_COST"NT_GBE_BASE"
CDS_LIB"mstr_discrete"
ROOM"NIC_SPRV";
"A"
$PN"1"27;
"B"
$PN"2"1;
%"GND"
"1","(-3350,2175)","0","mstr_symbols","I139";
;
SIZE"1B"
CDS_LIB"mstr_symbols"
VOLTAGE"0.0V"
BODY_TYPE"PLUMBING"
HDL_POWER"GND";
"A\NAC"1;
%"CAP"
"1","(-3650,2375)","0","mstr_discrete","I140";
;
PART_NUMBER"A36096-049"
VALUE"470PF"
LOCATION"C9G1"
MATERIAL"X7R"
VOLTAGE"50V"
PACK_TYPE"0402LF"
TOLERANCE"10%"
GROUP"NI_I210&RJ45"
CDS_SEC"1"
CDS_LIB"mstr_discrete"
ROOM"NIC_SPRV"
CDS_LOCATION"C9G1"
SEC"1"
BOM_COST"NT_GBE_BASE"
SEC_TYPE"0402LF";
"A"
$PN"1"25;
"B"
$PN"2"2;
%"GND"
"1","(-3650,2175)","0","mstr_symbols","I141";
;
SIZE"1B"
VOLTAGE"0.0V"
CDS_LIB"mstr_symbols"
BODY_TYPE"PLUMBING"
HDL_POWER"GND";
"A\NAC"2;
%"GND"
"1","(-3450,1700)","0","mstr_symbols","I146";
;
SIZE"1B"
VOLTAGE"0.0V"
CDS_LIB"mstr_symbols"
BODY_TYPE"PLUMBING"
HDL_POWER"GND";
"A\NAC"3;
%"CAP"
"1","(-3200,1050)","0","mstr_discrete","I152";
;
GROUP"NI_I210&RJ45"
LOCATION"C9G2"
VALUE"470PF"
PACK_TYPE"0402LF"
PART_NUMBER"A36096-049"
TOLERANCE"10%"
VOLTAGE"50V"
MATERIAL"X7R"
CDS_SEC"1"
CDS_LIB"mstr_discrete"
CDS_LOCATION"C9G2"
SEC"1"
BOM_COST"NT_GBE_BASE"
SEC_TYPE"0402LF"
ROOM"NIC_SPRV";
"A"
$PN"1"4;
"B"
$PN"2"5;
%"P3V3_STBY"
"1","(-3200,1300)","0","mstr_symbols","I153";
;
CDS_LIB"mstr_symbols"
SIZE"1B"
VOLTAGE"3.3V"
BODY_TYPE"PLUMBING"
HDL_POWER"P3V3_STBY";
"G\NAC"4;
%"GND"
"1","(-3200,850)","0","mstr_symbols","I155";
;
CDS_LIB"mstr_symbols"
SIZE"1B"
VOLTAGE"0.0V"
BODY_TYPE"PLUMBING"
HDL_POWER"GND";
"A\NAC"5;
%"RES"
"1","(-2875,1200)","4","mstr_discrete","I156";
;
WATTAGE"1/16W"
PACK_TYPE"0402"
LOCATION"R9G4"
MATERIAL"CHIP"
TOLERANCE"5%"
VALUE"0.0"
PART_NUMBER"G21497-005"
GROUP"NI_I210&RJ45"
BOM_COST"NT_GBE_BASE"
SEC_TYPE"0402"
ROOM"NIC_SPRV"
SEC"1"
CDS_LOCATION"R9G4"
CDS_LIB"mstr_discrete"
CDS_SEC"1";
"B"
$PN"2"4;
"A"
$PN"1"10;
%"RES"
"1","(-2800,1450)","0","mstr_discrete","I157";
;
TOLERANCE"1%"
WATTAGE"1/16W"
PART_NUMBER"G21796-009"
MATERIAL"CHIP"
LOCATION"R9G1"
VALUE"150.0"
PACK_TYPE"0402"
GROUP"NI_I210&RJ45"
SEC_TYPE"0402"
SEC"1"
BOM_COST"NT_GBE_BASE"
CDS_LIB"mstr_discrete"
CDS_LOCATION"R9G1"
ROOM"NIC_SPRV"
CDS_SEC"1";
"B"
$PN"2"11;
"A"
$PN"1"19;
%"CAP"
"1","(-3650,1300)","0","mstr_discrete","I159";
;
VOLTAGE"50V"
LOCATION"C9F22"
VALUE"470PF"
TOLERANCE"10%"
MATERIAL"X7R"
PART_NUMBER"A36096-049"
PACK_TYPE"0402LF"
GROUP"NI_I210&RJ45"
BOM_COST"NT_GBE_BASE"
SEC_TYPE"0402LF"
SEC"1"
CDS_LOCATION"C9F22"
ROOM"NIC_SPRV"
CDS_LIB"mstr_discrete"
CDS_SEC"1";
"A"
$PN"1"19;
"B"
$PN"2"6;
%"GND"
"1","(-3650,1100)","0","mstr_symbols","I160";
;
VOLTAGE"0.0V"
SIZE"1B"
CDS_LIB"mstr_symbols"
BODY_TYPE"PLUMBING"
HDL_POWER"GND";
"A\NAC"6;
%"GND"
"1","(-1250,2275)","0","mstr_symbols","I161";
;
CDS_LIB"mstr_symbols"
VOLTAGE"0.0V"
SIZE"1B"
BODY_TYPE"PLUMBING"
HDL_POWER"GND";
"A\NAC"7;
%"GND"
"1","(-1250,1125)","0","mstr_symbols","I162";
;
SIZE"1B"
VOLTAGE"0.0V"
CDS_LIB"mstr_symbols"
BODY_TYPE"PLUMBING"
HDL_POWER"GND";
"A\NAC"8;
%"CAP_A"
"1","(-6075,575)","0","dev_discrete","I46";
;
MATERIAL"X7R"
TOLERANCE"10%"
PACK_TYPE"0402V"
PART_NUMBER"A36096-030"
VOLTAGE"16V"
LOCATION"C9G4"
VALUE"0.1UF"
GROUP"NI_I210&RJ45"
CDS_LIB"dev_discrete"
ROOM"NIC_SPRV"
CDS_LOCATION"C9G4"
BOM_COST"NT_GBE_BASE"
CDS_SEC"1"
SEC_TYPE"0402V"
SEC"1";
"B"
$PN"2"9;
"A"
$PN"1"34;
%"CAP_A"
"1","(-6400,575)","0","dev_discrete","I47";
;
MATERIAL"X7R"
PACK_TYPE"0402V"
PART_NUMBER"A36096-030"
VALUE"0.1UF"
LOCATION"C9G6"
VOLTAGE"16V"
TOLERANCE"10%"
GROUP"NI_I210&RJ45"
CDS_LIB"dev_discrete"
CDS_LOCATION"C9G6"
CDS_SEC"1"
ROOM"NIC_SPRV"
BOM_COST"NT_GBE_BASE"
SEC_TYPE"0402V"
SEC"1";
"B"
$PN"2"9;
"A"
$PN"1"34;
%"CAP"
"1","(-6750,575)","0","mstr_discrete","I48";
;
CDS_SEC"1"
VALUE"1.0UF"
PART_NUMBER"G71842-007"
PACK_TYPE"0402"
VOLTAGE"16V"
MATERIAL"X7S"
LOCATION"C9G5"
TOLERANCE"10%"
GROUP"NI_I210&RJ45"
CDS_LIB"mstr_discrete"
BOM_COST"NT_GBE_BASE"
SEC_TYPE"0402"
SEC"1"
CDS_LOCATION"C9G5"
ROOM"NIC_SPRV";
"A"
$PN"1"34;
"B"
$PN"2"9;
%"GND"
"1","(-6750,275)","0","mstr_symbols","I50";
;
VOLTAGE"0.0V"
CDS_LIB"mstr_symbols"
SIZE"1B"
BODY_TYPE"PLUMBING"
HDL_POWER"GND";
"A\NAC"9;
%"RES"
"1","(-3275,3775)","0","mstr_discrete","I75";
;
CDS_SEC"1"
MATERIAL"CHIP"
WATTAGE"1/16W"
LOCATION"R9G9"
VALUE"0.0"
PACK_TYPE"0402"
PART_NUMBER"G21497-005"
TOLERANCE"5%"
GROUP"NI_I210&RJ45"
BOM_COST"NT_GBE_BASE"
ROOM"NIC_SPRV"
CDS_LIB"mstr_discrete"
CDS_LOCATION"R9G9"
SEC"1"
SEC_TYPE"0402";
"B"
$PN"2"33;
"A"
$PN"1"26;
%"RES"
"1","(-3275,3725)","0","mstr_discrete","I76";
;
CDS_SEC"1"
MATERIAL"CHIP"
WATTAGE"1/16W"
PACK_TYPE"0402"
VALUE"0.0"
PART_NUMBER"G21497-005"
LOCATION"R9G11"
TOLERANCE"5%"
GROUP"NI_I210&RJ45"
BOM_COST"NT_GBE_BASE"
ROOM"NIC_SPRV"
CDS_LIB"mstr_discrete"
CDS_LOCATION"R9G11"
SEC"1"
SEC_TYPE"0402";
"B"
$PN"2"44;
"A"
$PN"1"28;
%"RES"
"1","(-3275,3675)","0","mstr_discrete","I77";
;
CDS_SEC"1"
MATERIAL"CHIP"
PART_NUMBER"G21497-005"
VALUE"0.0"
WATTAGE"1/16W"
LOCATION"R9G18"
PACK_TYPE"0402"
TOLERANCE"5%"
GROUP"NI_I210&RJ45"
ROOM"NIC_SPRV"
BOM_COST"NT_GBE_BASE"
CDS_LIB"mstr_discrete"
CDS_LOCATION"R9G18"
SEC"1"
SEC_TYPE"0402";
"B"
$PN"2"43;
"A"
$PN"1"20;
%"RES"
"1","(-3275,3625)","0","mstr_discrete","I78";
;
CDS_SEC"1"
PART_NUMBER"G21497-005"
MATERIAL"CHIP"
WATTAGE"1/16W"
PACK_TYPE"0402"
VALUE"0.0"
LOCATION"R9G17"
TOLERANCE"5%"
GROUP"NI_I210&RJ45"
ROOM"NIC_SPRV"
BOM_COST"NT_GBE_BASE"
CDS_LIB"mstr_discrete"
CDS_LOCATION"R9G17"
SEC"1"
SEC_TYPE"0402";
"B"
$PN"2"45;
"A"
$PN"1"29;
%"RES"
"1","(-3275,3575)","0","mstr_discrete","I79";
;
CDS_SEC"1"
MATERIAL"CHIP"
PACK_TYPE"0402"
PART_NUMBER"G21497-005"
VALUE"0.0"
WATTAGE"1/16W"
LOCATION"R9G19"
TOLERANCE"5%"
GROUP"NI_I210&RJ45"
ROOM"NIC_SPRV"
BOM_COST"NT_GBE_BASE"
CDS_LIB"mstr_discrete"
CDS_LOCATION"R9G19"
SEC"1"
SEC_TYPE"0402";
"B"
$PN"2"42;
"A"
$PN"1"22;
%"RES"
"1","(-3275,3525)","0","mstr_discrete","I80";
;
CDS_SEC"1"
PART_NUMBER"G21497-005"
PACK_TYPE"0402"
MATERIAL"CHIP"
WATTAGE"1/16W"
VALUE"0.0"
LOCATION"R9G20"
TOLERANCE"5%"
GROUP"NI_I210&RJ45"
BOM_COST"NT_GBE_BASE"
ROOM"NIC_SPRV"
CDS_LIB"mstr_discrete"
CDS_LOCATION"R9G20"
SEC"1"
SEC_TYPE"0402";
"B"
$PN"2"41;
"A"
$PN"1"21;
%"RES"
"1","(-3275,3475)","0","mstr_discrete","I81";
;
CDS_SEC"1"
PART_NUMBER"G21497-005"
MATERIAL"CHIP"
VALUE"0.0"
PACK_TYPE"0402"
LOCATION"R9G24"
TOLERANCE"5%"
GROUP"NI_I210&RJ45"
WATTAGE"1/16W"
BOM_COST"NT_GBE_BASE"
ROOM"NIC_SPRV"
CDS_LIB"mstr_discrete"
CDS_LOCATION"R9G24"
SEC"1"
SEC_TYPE"0402";
"B"
$PN"2"31;
"A"
$PN"1"24;
%"RES"
"1","(-3275,3425)","0","mstr_discrete","I82";
;
CDS_SEC"1"
WATTAGE"1/16W"
VALUE"0.0"
MATERIAL"CHIP"
PACK_TYPE"0402"
LOCATION"R9G22"
PART_NUMBER"G21497-005"
TOLERANCE"5%"
GROUP"NI_I210&RJ45"
CDS_LOCATION"R9G22"
CDS_LIB"mstr_discrete"
BOM_COST"NT_GBE_BASE"
ROOM"NIC_SPRV"
SEC"1"
SEC_TYPE"0402";
"B"
$PN"2"32;
"A"
$PN"1"23;
%"CAP"
"2","(-2875,4425)","0","mstr_discrete","I99";
;
CDS_SEC"1"
VALUE"4700PF"
PACK_TYPE"0402LF"
TOLERANCE"10%"
VOLTAGE"50V"
LOCATION"C9G9"
PART_NUMBER"A36096-066"
MATERIAL"EMPTY"
GROUP"NI_I210&RJ45"
NO_XNET_CONNECTION"1"
ROOM"NIC_SPRV"
BOM_COST"NT_GBE_BASE"
CDS_LIB"mstr_discrete"
CDS_LOCATION"C9G9"
SEC"1"
SEC_TYPE"0402LF";
"A"
$PN"1"26;
"B"
$PN"2"46;
END.
